(kicad_pcb
	(version 20260206)
	(generator "pcbnew")
	(generator_version "10.0")
	(general
		(thickness 1.6)
		(legacy_teardrops no)
	)
	(paper "A4")
	(title_block
		(title "Bryce Canyon_IOM_IOC_16318-2_OCP.brd")
		(comment 1 "Bryce Canyon / footprints 623-630 of 1605")
	)
	(layers
		(0 "F.Cu" signal "TOP")
		(4 "In1.Cu" signal "L2GND")
		(6 "In2.Cu" signal "L3")
		(8 "In3.Cu" signal "L4VCC")
		(10 "In4.Cu" signal "L5VCC")
		(12 "In5.Cu" signal "L6")
		(14 "In6.Cu" signal "L7GND")
		(2 "B.Cu" signal "BOTTOM")
		(9 "F.Adhes" user "F.Adhesive")
		(11 "B.Adhes" user "B.Adhesive")
		(13 "F.Paste" user "Package Geometry/Pastemask Top")
		(15 "B.Paste" user "Package Geometry/Pastemask Bottom")
		(5 "F.SilkS" user "Ref Des/Silkscreen Top")
		(7 "B.SilkS" user "Ref Des/Silkscreen Bottom")
		(1 "F.Mask" user "Board Geometry/Soldermask Top")
		(3 "B.Mask" user "Board Geometry/Soldermask Bottom")
		(17 "Dwgs.User" user "User.Drawings")
		(19 "Cmts.User" user "User.Comments")
		(21 "Eco1.User" user "User.Eco1")
		(23 "Eco2.User" user "User.Eco2")
		(25 "Edge.Cuts" user "Board Geometry/Outline")
		(27 "Margin" user)
		(31 "F.CrtYd" user "Package Geometry/Place Bound Top")
		(29 "B.CrtYd" user "Package Geometry/Place Bound Bottom")
		(35 "F.Fab" user "Ref Des/Assembly Top")
		(33 "B.Fab" user "Ref Des/Assembly Bottom")
	)
	(footprint ""
		(layer "F.Cu")
		(at 183.3626 -142.3924 -90)
		(property "Reference" "R472"
			(at 0 0 270)
			(layer "F.SilkS")
			(hide yes)
			(effects
				(font
					(size 1.27 1.27)
				)
			)
		)
		(property "Value" "100KR2F-L1-GP"
			(at 0.064008 -3.993896 270)
			(unlocked yes)
			(layer "F.Fab")
			(hide yes)
			(effects
				(font
					(size 1.016 1.016)
					(thickness 0.1524)
				)
			)
		)
		(property "Device Type" "R402H16"
			(at 0.064008 -5.517896 270)
			(unlocked yes)
			(layer "F.Fab")
			(hide yes)
			(effects
				(font
					(size 1.016 1.016)
					(thickness 0.1524)
				)
			)
		)
		(duplicate_pad_numbers_are_jumpers no)
		(fp_line
			(start -0.508 -0.9398)
			(end -0.508 0.9398)
			(stroke
				(width 0.1524)
				(type default)
			)
			(layer "F.SilkS")
		)
		(fp_line
			(start 0.508 -0.9398)
			(end -0.508 -0.9398)
			(stroke
				(width 0.1524)
				(type default)
			)
			(layer "F.SilkS")
		)
		(fp_rect
			(start -0.508 0.9398)
			(end 0.508 -0.9398)
			(stroke
				(width 0)
				(type default)
			)
			(fill no)
			(layer "F.CrtYd")
		)
		(fp_rect
			(start -0.508 0.9398)
			(end 0.508 -0.9398)
			(stroke
				(width 0)
				(type default)
			)
			(fill no)
			(layer "F.Fab")
		)
		(pad "1" smd custom
			(at 0 -0.4445 270)
			(size 0.1397 0.1397)
			(layers "F.Cu" "F.Mask" "F.Paste")
			(net "AGND_P5V")
			(options
				(clearance outline)
				(anchor circle)
			)
			(primitives
				(gr_poly
					(pts
						(arc
							(start -0.1778 -0.2794)
							(mid -0.249642 -0.249642)
							(end -0.2794 -0.1778)
						)
						(arc
							(start -0.2794 0.1778)
							(mid -0.249642 0.249642)
							(end -0.1778 0.2794)
						)
						(arc
							(start 0.1778 0.2794)
							(mid 0.249642 0.249642)
							(end 0.2794 0.1778)
						)
						(arc
							(start 0.2794 -0.1778)
							(mid 0.249642 -0.249642)
							(end 0.1778 -0.2794)
						)
					)
					(width 0)
					(fill yes)
				)
			)
		)
		(pad "2" smd custom
			(at 0 0.4445 270)
			(size 0.1397 0.1397)
			(layers "F.Cu" "F.Mask" "F.Paste")
			(net "P5V_MODE")
			(options
				(clearance outline)
				(anchor circle)
			)
			(primitives
				(gr_poly
					(pts
						(arc
							(start -0.1778 -0.2794)
							(mid -0.249642 -0.249642)
							(end -0.2794 -0.1778)
						)
						(arc
							(start -0.2794 0.1778)
							(mid -0.249642 0.249642)
							(end -0.1778 0.2794)
						)
						(arc
							(start 0.1778 0.2794)
							(mid 0.249642 0.249642)
							(end 0.2794 0.1778)
						)
						(arc
							(start 0.2794 -0.1778)
							(mid 0.249642 -0.249642)
							(end 0.1778 -0.2794)
						)
					)
					(width 0)
					(fill yes)
				)
			)
		)
	)
	(footprint ""
		(layer "F.Cu")
		(at 37.299646 -174.67961 90)
		(property "Reference" "C184"
			(at 0 0 90)
			(layer "F.SilkS")
			(hide yes)
			(effects
				(font
					(size 1.27 1.27)
				)
			)
		)
		(property "Value" "SC68P50V2JN-2-GP"
			(at 1.1811 -2.7051 90)
			(unlocked yes)
			(layer "F.Fab")
			(hide yes)
			(effects
				(font
					(size 1.016 1.016)
					(thickness 0.1524)
				)
			)
		)
		(property "Device Type" "C402H22"
			(at 1.1811 -4.2291 90)
			(unlocked yes)
			(layer "F.Fab")
			(hide yes)
			(effects
				(font
					(size 1.016 1.016)
					(thickness 0.1524)
				)
			)
		)
		(duplicate_pad_numbers_are_jumpers no)
		(fp_rect
			(start -0.4318 0.9525)
			(end 0.4318 -0.9525)
			(stroke
				(width 0)
				(type default)
			)
			(fill no)
			(layer "F.CrtYd")
		)
		(fp_rect
			(start -0.4318 0.9525)
			(end 0.4318 -0.9525)
			(stroke
				(width 0)
				(type default)
			)
			(fill no)
			(layer "F.Fab")
		)
		(pad "1" smd custom
			(at 0 -0.4445 90)
			(size 0.1524 0.1524)
			(layers "F.Cu" "F.Mask" "F.Paste")
			(net "P3V3_STBY_VFB")
			(options
				(clearance outline)
				(anchor circle)
			)
			(primitives
				(gr_poly
					(pts
						(arc
							(start 0.3048 -0.2032)
							(mid 0.275042 -0.275042)
							(end 0.2032 -0.3048)
						)
						(arc
							(start -0.2032 -0.3048)
							(mid -0.275042 -0.275042)
							(end -0.3048 -0.2032)
						)
						(arc
							(start -0.3048 0.2032)
							(mid -0.275042 0.275042)
							(end -0.2032 0.3048)
						)
						(arc
							(start 0.2032 0.3048)
							(mid 0.275042 0.275042)
							(end 0.3048 0.2032)
						)
					)
					(width 0)
					(fill yes)
				)
			)
		)
		(pad "2" smd custom
			(at 0 0.4445 90)
			(size 0.1524 0.1524)
			(layers "F.Cu" "F.Mask" "F.Paste")
			(net "P3V3_STBY_VFB_R")
			(options
				(clearance outline)
				(anchor circle)
			)
			(primitives
				(gr_poly
					(pts
						(arc
							(start 0.3048 -0.2032)
							(mid 0.275042 -0.275042)
							(end 0.2032 -0.3048)
						)
						(arc
							(start -0.2032 -0.3048)
							(mid -0.275042 -0.275042)
							(end -0.3048 -0.2032)
						)
						(arc
							(start -0.3048 0.2032)
							(mid -0.275042 0.275042)
							(end -0.2032 0.3048)
						)
						(arc
							(start 0.2032 0.3048)
							(mid 0.275042 0.275042)
							(end 0.3048 0.2032)
						)
					)
					(width 0)
					(fill yes)
				)
			)
		)
	)
	(footprint ""
		(layer "F.Cu")
		(at 61.468 -149.5806 90)
		(property "Reference" "R338"
			(at 0 0 90)
			(layer "F.SilkS")
			(hide yes)
			(effects
				(font
					(size 1.27 1.27)
				)
			)
		)
		(property "Value" "8K2R2J-3-GP"
			(at 0.063754 -3.993896 90)
			(unlocked yes)
			(layer "F.Fab")
			(hide yes)
			(effects
				(font
					(size 1.016 1.016)
					(thickness 0.1524)
				)
			)
		)
		(property "Device Type" "R402H16"
			(at 0.063754 -5.517896 90)
			(unlocked yes)
			(layer "F.Fab")
			(hide yes)
			(effects
				(font
					(size 1.016 1.016)
					(thickness 0.1524)
				)
			)
		)
		(duplicate_pad_numbers_are_jumpers no)
		(fp_line
			(start 0.508 -0.9398)
			(end -0.508 -0.9398)
			(stroke
				(width 0.1524)
				(type default)
			)
			(layer "F.SilkS")
		)
		(fp_line
			(start -0.508 -0.9398)
			(end -0.508 0.9398)
			(stroke
				(width 0.1524)
				(type default)
			)
			(layer "F.SilkS")
		)
		(fp_rect
			(start -0.508 0.9398)
			(end 0.508 -0.9398)
			(stroke
				(width 0)
				(type default)
			)
			(fill no)
			(layer "F.CrtYd")
		)
		(fp_rect
			(start -0.508 0.9398)
			(end 0.508 -0.9398)
			(stroke
				(width 0)
				(type default)
			)
			(fill no)
			(layer "F.Fab")
		)
		(pad "1" smd custom
			(at 0 -0.4445 90)
			(size 0.1397 0.1397)
			(layers "F.Cu" "F.Mask" "F.Paste")
			(net "PD_USB2AVRES")
			(options
				(clearance outline)
				(anchor circle)
			)
			(primitives
				(gr_poly
					(pts
						(arc
							(start -0.1778 -0.2794)
							(mid -0.249642 -0.249642)
							(end -0.2794 -0.1778)
						)
						(arc
							(start -0.2794 0.1778)
							(mid -0.249642 0.249642)
							(end -0.1778 0.2794)
						)
						(arc
							(start 0.1778 0.2794)
							(mid 0.249642 0.249642)
							(end 0.2794 0.1778)
						)
						(arc
							(start 0.2794 -0.1778)
							(mid 0.249642 -0.249642)
							(end 0.1778 -0.2794)
						)
					)
					(width 0)
					(fill yes)
				)
			)
		)
		(pad "2" smd custom
			(at 0 0.4445 90)
			(size 0.1397 0.1397)
			(layers "F.Cu" "F.Mask" "F.Paste")
			(net "GND")
			(options
				(clearance outline)
				(anchor circle)
			)
			(primitives
				(gr_poly
					(pts
						(arc
							(start -0.1778 -0.2794)
							(mid -0.249642 -0.249642)
							(end -0.2794 -0.1778)
						)
						(arc
							(start -0.2794 0.1778)
							(mid -0.249642 0.249642)
							(end -0.1778 0.2794)
						)
						(arc
							(start 0.1778 0.2794)
							(mid 0.249642 0.249642)
							(end 0.2794 0.1778)
						)
						(arc
							(start 0.2794 -0.1778)
							(mid 0.249642 -0.249642)
							(end 0.1778 -0.2794)
						)
					)
					(width 0)
					(fill yes)
				)
			)
		)
	)
	(footprint ""
		(layer "F.Cu")
		(at 194.136772 -88.6968 135)
		(property "Reference" "VIA22"
			(at 0 0 135)
			(layer "F.SilkS")
			(hide yes)
			(effects
				(font
					(size 1.27 1.27)
				)
			)
		)
		(property "Value" "85OHM-8L-1D6MM-L16L18-GP"
			(at 4.064105 0.609655 135)
			(unlocked yes)
			(layer "F.Fab")
			(hide yes)
			(effects
				(font
					(size 1.016 1.016)
					(thickness 0.1524)
				)
			)
		)
		(property "Device Type" "VIA-PCIE-4P-368076"
			(at 4.064105 -0.914474 135)
			(unlocked yes)
			(layer "F.Fab")
			(hide yes)
			(effects
				(font
					(size 1.016 1.016)
					(thickness 0.1524)
				)
			)
		)
		(duplicate_pad_numbers_are_jumpers no)
		(fp_poly
			(pts
				(xy -1.841491 -0.381057) (xy 1.841509 -0.381058) (xy 1.841508 0.380942) (xy -1.841491 0.380942)
			)
			(stroke
				(width 0)
				(type default)
			)
			(fill no)
			(layer "F.CrtYd")
		)
		(fp_poly
			(pts
				(xy -1.841491 -0.381057) (xy 1.841509 -0.381058) (xy 1.841508 0.380942) (xy -1.841491 0.380942)
			)
			(stroke
				(width 0)
				(type default)
			)
			(fill no)
			(layer "F.Fab")
		)
		(pad "1" thru_hole circle
			(at -1.460499 0 135)
			(size 0.508 0.508)
			(drill 0.254)
			(layers "*.Cu" "*.Mask")
			(remove_unused_layers no)
			(net "GND")
			(clearance 0.127)
			(thermal_gap 0.127)
		)
		(pad "2" thru_hole circle
			(at -0.4445 0 135)
			(size 0.508 0.508)
			(drill 0.254)
			(layers "*.Cu" "*.Mask")
			(remove_unused_layers no)
			(net "PCIE_COMP_TO_IOM_12_DP")
			(clearance 0.127)
			(thermal_gap 0.127)
		)
		(pad "3" thru_hole circle
			(at 0.4445 0 135)
			(size 0.508 0.508)
			(drill 0.254)
			(layers "*.Cu" "*.Mask")
			(remove_unused_layers no)
			(net "PCIE_COMP_TO_IOM_12_DN")
			(clearance 0.127)
			(thermal_gap 0.127)
		)
		(pad "4" thru_hole circle
			(at 1.460499 0 135)
			(size 0.508 0.508)
			(drill 0.254)
			(layers "*.Cu" "*.Mask")
			(remove_unused_layers no)
			(net "GND")
			(clearance 0.127)
			(thermal_gap 0.127)
		)
	)
	(footprint ""
		(layer "F.Cu")
		(at 155.499816 -187.999878)
		(property "Reference" ""
			(at 0 0 0)
			(layer "F.SilkS")
			(hide yes)
			(effects
				(font
					(size 1.27 1.27)
				)
			)
		)
		(property "Value" "*"
			(at -6.38175 0.19685 0)
			(unlocked yes)
			(layer "F.Fab")
			(hide yes)
			(effects
				(font
					(size 1.016 1.016)
					(thickness 0.1524)
				)
			)
		)
		(duplicate_pad_numbers_are_jumpers no)
		(fp_poly
			(pts
				(arc
					(start 5.0673 0)
					(mid -5.0673 0)
					(end 5.0673 0)
				)
			)
			(stroke
				(width 0)
				(type default)
			)
			(fill no)
			(layer "B.CrtYd")
		)
		(fp_poly
			(pts
				(arc
					(start 5.0673 0)
					(mid -5.0673 0)
					(end 5.0673 0)
				)
			)
			(stroke
				(width 0)
				(type default)
			)
			(fill no)
			(layer "F.CrtYd")
		)
		(fp_poly
			(pts
				(arc
					(start 5.0673 0)
					(mid -5.0673 0)
					(end 5.0673 0)
				)
			)
			(stroke
				(width 0)
				(type default)
			)
			(fill no)
			(layer "B.Fab")
		)
		(fp_poly
			(pts
				(arc
					(start 5.0673 0)
					(mid -5.0673 0)
					(end 5.0673 0)
				)
			)
			(stroke
				(width 0)
				(type default)
			)
			(fill no)
			(layer "F.Fab")
		)
		(pad "1" thru_hole circle
			(at 0 0)
			(size 9.525 9.525)
			(drill 3.5052)
			(layers "*.Cu" "*.Mask")
			(remove_unused_layers no)
			(net "Net_13")
			(clearance -2.5019)
			(thermal_gap 0.3048)
			(padstack
				(mode front_inner_back)
				(layer "Inner"
					(shape circle)
					(size 3.9116 3.9116)
					(clearance 0.3048)
				)
				(layer "B.Cu"
					(shape circle)
					(size 9.525 9.525)
					(clearance -2.5019)
				)
			)
		)
	)
	(footprint ""
		(layer "F.Cu")
		(at 68.4784 -134.5692)
		(property "Reference" "R52"
			(at 0 0 0)
			(layer "F.SilkS")
			(hide yes)
			(effects
				(font
					(size 1.27 1.27)
				)
			)
		)
		(property "Value" "33R2F-3-GP"
			(at 0.064008 -3.993896 0)
			(unlocked yes)
			(layer "F.Fab")
			(hide yes)
			(effects
				(font
					(size 1.016 1.016)
					(thickness 0.1524)
				)
			)
		)
		(property "Device Type" "R402H16"
			(at 0.064008 -5.517896 0)
			(unlocked yes)
			(layer "F.Fab")
			(hide yes)
			(effects
				(font
					(size 1.016 1.016)
					(thickness 0.1524)
				)
			)
		)
		(duplicate_pad_numbers_are_jumpers no)
		(fp_line
			(start -0.508 -0.9398)
			(end -0.508 0.9398)
			(stroke
				(width 0.1524)
				(type default)
			)
			(layer "F.SilkS")
		)
		(fp_line
			(start 0.508 -0.9398)
			(end -0.508 -0.9398)
			(stroke
				(width 0.1524)
				(type default)
			)
			(layer "F.SilkS")
		)
		(fp_rect
			(start -0.508 0.9398)
			(end 0.508 -0.9398)
			(stroke
				(width 0)
				(type default)
			)
			(fill no)
			(layer "F.CrtYd")
		)
		(fp_rect
			(start -0.508 0.9398)
			(end 0.508 -0.9398)
			(stroke
				(width 0)
				(type default)
			)
			(fill no)
			(layer "F.Fab")
		)
		(pad "1" smd custom
			(at 0 -0.4445)
			(size 0.1397 0.1397)
			(layers "F.Cu" "F.Mask" "F.Paste")
			(net "FP_PWRBTN")
			(options
				(clearance outline)
				(anchor circle)
			)
			(primitives
				(gr_poly
					(pts
						(arc
							(start -0.1778 -0.2794)
							(mid -0.249642 -0.249642)
							(end -0.2794 -0.1778)
						)
						(arc
							(start -0.2794 0.1778)
							(mid -0.249642 0.249642)
							(end -0.1778 0.2794)
						)
						(arc
							(start 0.1778 0.2794)
							(mid 0.249642 0.249642)
							(end 0.2794 0.1778)
						)
						(arc
							(start 0.2794 -0.1778)
							(mid 0.249642 -0.249642)
							(end 0.1778 -0.2794)
						)
					)
					(width 0)
					(fill yes)
				)
			)
		)
		(pad "2" smd custom
			(at 0 0.4445)
			(size 0.1397 0.1397)
			(layers "F.Cu" "F.Mask" "F.Paste")
			(net "PWRBTN_OUT_N")
			(options
				(clearance outline)
				(anchor circle)
			)
			(primitives
				(gr_poly
					(pts
						(arc
							(start -0.1778 -0.2794)
							(mid -0.249642 -0.249642)
							(end -0.2794 -0.1778)
						)
						(arc
							(start -0.2794 0.1778)
							(mid -0.249642 0.249642)
							(end -0.1778 0.2794)
						)
						(arc
							(start 0.1778 0.2794)
							(mid 0.249642 0.249642)
							(end 0.2794 0.1778)
						)
						(arc
							(start 0.2794 -0.1778)
							(mid 0.249642 -0.249642)
							(end 0.1778 -0.2794)
						)
					)
					(width 0)
					(fill yes)
				)
			)
		)
	)
	(footprint ""
		(layer "F.Cu")
		(at 63.04661 -156.181298 180)
		(property "Reference" "R387"
			(at 0 0 180)
			(layer "F.SilkS")
			(hide yes)
			(effects
				(font
					(size 1.27 1.27)
				)
			)
		)
		(property "Value" "4K7R2F-GP"
			(at 0.064008 -3.993896 180)
			(unlocked yes)
			(layer "F.Fab")
			(hide yes)
			(effects
				(font
					(size 1.016 1.016)
					(thickness 0.1524)
				)
			)
		)
		(property "Device Type" "R402H16"
			(at 0.064008 -5.517896 180)
			(unlocked yes)
			(layer "F.Fab")
			(hide yes)
			(effects
				(font
					(size 1.016 1.016)
					(thickness 0.1524)
				)
			)
		)
		(duplicate_pad_numbers_are_jumpers no)
		(fp_line
			(start 0.508 -0.9398)
			(end -0.508 -0.9398)
			(stroke
				(width 0.1524)
				(type default)
			)
			(layer "F.SilkS")
		)
		(fp_line
			(start -0.508 -0.9398)
			(end -0.508 0.9398)
			(stroke
				(width 0.1524)
				(type default)
			)
			(layer "F.SilkS")
		)
		(fp_rect
			(start -0.508 0.9398)
			(end 0.508 -0.9398)
			(stroke
				(width 0)
				(type default)
			)
			(fill no)
			(layer "F.CrtYd")
		)
		(fp_rect
			(start -0.508 0.9398)
			(end 0.508 -0.9398)
			(stroke
				(width 0)
				(type default)
			)
			(fill no)
			(layer "F.Fab")
		)
		(pad "1" smd custom
			(at 0 -0.4445 180)
			(size 0.1397 0.1397)
			(layers "F.Cu" "F.Mask" "F.Paste")
			(net "GND")
			(options
				(clearance outline)
				(anchor circle)
			)
			(primitives
				(gr_poly
					(pts
						(arc
							(start -0.1778 -0.2794)
							(mid -0.249642 -0.249642)
							(end -0.2794 -0.1778)
						)
						(arc
							(start -0.2794 0.1778)
							(mid -0.249642 0.249642)
							(end -0.1778 0.2794)
						)
						(arc
							(start 0.1778 0.2794)
							(mid 0.249642 0.249642)
							(end 0.2794 0.1778)
						)
						(arc
							(start 0.2794 -0.1778)
							(mid 0.249642 -0.249642)
							(end 0.1778 -0.2794)
						)
					)
					(width 0)
					(fill yes)
				)
			)
		)
		(pad "2" smd custom
			(at 0 0.4445 180)
			(size 0.1397 0.1397)
			(layers "F.Cu" "F.Mask" "F.Paste")
			(net "NCSI_TXD1")
			(options
				(clearance outline)
				(anchor circle)
			)
			(primitives
				(gr_poly
					(pts
						(arc
							(start -0.1778 -0.2794)
							(mid -0.249642 -0.249642)
							(end -0.2794 -0.1778)
						)
						(arc
							(start -0.2794 0.1778)
							(mid -0.249642 0.249642)
							(end -0.1778 0.2794)
						)
						(arc
							(start 0.1778 0.2794)
							(mid 0.249642 0.249642)
							(end 0.2794 0.1778)
						)
						(arc
							(start 0.2794 -0.1778)
							(mid 0.249642 -0.249642)
							(end 0.1778 -0.2794)
						)
					)
					(width 0)
					(fill yes)
				)
			)
		)
	)
	(footprint ""
		(layer "F.Cu")
		(at 208.055972 -66.6496 90)
		(property "Reference" "C319"
			(at 0 0 90)
			(layer "F.SilkS")
			(hide yes)
			(effects
				(font
					(size 1.27 1.27)
				)
			)
		)
		(property "Value" "SCD01U16V1KX-GP"
			(at -2.8321 -1.7399 90)
			(unlocked yes)
			(layer "F.Fab")
			(hide yes)
			(effects
				(font
					(size 1.016 1.016)
					(thickness 0.1524)
				)
			)
		)
		(property "Device Type" "C0201H13"
			(at -2.8321 -3.2639 90)
			(unlocked yes)
			(layer "F.Fab")
			(hide yes)
			(effects
				(font
					(size 1.016 1.016)
					(thickness 0.1524)
				)
			)
		)
		(duplicate_pad_numbers_are_jumpers no)
		(fp_rect
			(start -0.2794 0.6477)
			(end 0.2794 -0.6477)
			(stroke
				(width 0)
				(type default)
			)
			(fill no)
			(layer "F.CrtYd")
		)
		(fp_rect
			(start -0.2794 0.6477)
			(end 0.2794 -0.6477)
			(stroke
				(width 0)
				(type default)
			)
			(fill no)
			(layer "F.Fab")
		)
		(pad "1" smd custom
			(at 0 -0.2794 90)
			(size 0.0762 0.0762)
			(layers "F.Cu" "F.Mask" "F.Paste")
			(net "PHY_IOC_TO_CON_B_2_DP_C")
			(options
				(clearance outline)
				(anchor circle)
			)
			(primitives
				(gr_poly
					(pts
						(arc
							(start 0.1524 -0.127)
							(mid 0.137521 -0.162921)
							(end 0.1016 -0.1778)
						)
						(arc
							(start -0.1016 -0.1778)
							(mid -0.137521 -0.162921)
							(end -0.1524 -0.127)
						)
						(arc
							(start -0.1524 0.127)
							(mid -0.137521 0.162921)
							(end -0.1016 0.1778)
						)
						(arc
							(start 0.1016 0.1778)
							(mid 0.137521 0.162921)
							(end 0.1524 0.127)
						)
					)
					(width 0)
					(fill yes)
				)
			)
		)
		(pad "2" smd custom
			(at 0 0.2794 90)
			(size 0.0762 0.0762)
			(layers "F.Cu" "F.Mask" "F.Paste")
			(net "PHY_IOC_TO_CON_B_2_DP")
			(options
				(clearance outline)
				(anchor circle)
			)
			(primitives
				(gr_poly
					(pts
						(arc
							(start 0.1524 -0.127)
							(mid 0.137521 -0.162921)
							(end 0.1016 -0.1778)
						)
						(arc
							(start -0.1016 -0.1778)
							(mid -0.137521 -0.162921)
							(end -0.1524 -0.127)
						)
						(arc
							(start -0.1524 0.127)
							(mid -0.137521 0.162921)
							(end -0.1016 0.1778)
						)
						(arc
							(start 0.1016 0.1778)
							(mid 0.137521 0.162921)
							(end 0.1524 0.127)
						)
					)
					(width 0)
					(fill yes)
				)
			)
		)
	)
)
